(kicad_pcb
	(version 20221018)
	(generator pcbnew)
	(general
    (thickness 1.562)
  )
	(paper "A4")
	(title_block
    (title "Thunderbolt PCIe Adaper")
    (date "2024-07-09")
    (rev "1.0.3")
    (comment 1 "www.antmicro.com")
    (comment 2 "Antmicro Ltd.")
		(comment 9 "footprints 53-57 of 271")
	)
	(layers
    (0 "F.Cu" signal)
    (1 "In1.Cu" signal)
    (2 "In2.Cu" signal)
    (3 "In3.Cu" signal)
    (4 "In4.Cu" signal)
    (31 "B.Cu" signal)
    (32 "B.Adhes" user "B.Adhesive")
    (33 "F.Adhes" user "F.Adhesive")
    (34 "B.Paste" user)
    (35 "F.Paste" user)
    (36 "B.SilkS" user "B.Silkscreen")
    (37 "F.SilkS" user "F.Silkscreen")
    (38 "B.Mask" user)
    (39 "F.Mask" user)
    (40 "Dwgs.User" user "User.Drawings")
    (41 "Cmts.User" user "User.Comments")
    (42 "Eco1.User" user "User.Eco1")
    (43 "Eco2.User" user "User.Eco2")
    (44 "Edge.Cuts" user)
    (45 "Margin" user)
    (46 "B.CrtYd" user "B.Courtyard")
    (47 "F.CrtYd" user "F.Courtyard")
    (48 "B.Fab" user)
    (49 "F.Fab" user)
  )
	(footprint "antmicro-footprints:C_1206_3216Metric" (layer "F.Cu")
    (at 113.470001 64.255 90)
    (descr "Capacitor SMD 1206")
    (tags "capacitor SMD 1206")
    (property "Author" "Antmicro")
    (property "Dielectric" "")
    (property "License" "Apache-2.0")
    (property "MPN" "3216X5R1V226M160AC")
    (property "Manufacturer" "TDK")
    (property "Sheetfile" "power.kicad_sch")
    (property "Sheetname" "Power")
    (property "Val" "22u")
    (property "Voltage" "35V")
    (property "ki_description" "SMD Multilayer Ceramic Capacitors, 22µF, 35V, X5R, 1206 [2316 Metric], 20% ")
    (property "ki_keywords" "1206, SMT, CAPACITOR, PASSIVE, CERAMIC, MLCC")
    (attr smd)
    (fp_text reference "C17" (at -4.452 0.321999 90) (layer "F.SilkS")
        (effects (font (size 0.7 0.7) (thickness 0.15)) (justify left bottom))
    )
    (fp_text value "C_22u_1206_35V" (at 0 2.101 90) (layer "F.Fab")
        (effects (font (size 0.7 0.7) (thickness 0.15)) (justify left bottom))
    )
    (fp_text user "License: Apache-2.0" (at -2.625 6.501 90) (layer "F.Fab") hide
        (effects (font (size 0.7 0.7) (thickness 0.15)) (justify left bottom))
    )
    (fp_text user "Author: Antmicro" (at -2.625 5.301 90) (layer "F.Fab") hide
        (effects (font (size 0.7 0.7) (thickness 0.15)) (justify left bottom))
    )
    (fp_text user "${REFERENCE}" (at -2.625 4.101 90) (layer "F.Fab") hide
        (effects (font (size 0.7 0.7) (thickness 0.15)) (justify left bottom))
    )
    (fp_line (start 0.8 -0.899) (end -0.8 -0.899)
      (stroke (width 0.15) (type solid)) (layer "F.SilkS"))
    (fp_line (start 0.8 0.901) (end -0.8 0.901)
      (stroke (width 0.15) (type solid)) (layer "F.SilkS"))
    (fp_rect (start -2.325 -1.15) (end 2.325 1.15)
      (stroke (width 0.05) (type default)) (fill none) (layer "F.CrtYd"))
    (fp_rect (start -1.6 -0.799) (end 1.6 0.801)
      (stroke (width 0.15) (type solid)) (fill none) (layer "F.Fab"))
    (pad "1" smd roundrect (at -1.5 0.001 90) (size 1.15 1.8) (layers "F.Cu" "F.Paste" "F.Mask") (roundrect_rratio 0.25)
      (net 1 "GND") (pintype "passive"))
    (pad "2" smd roundrect (at 1.5 0.001 90) (size 1.15 1.8) (layers "F.Cu" "F.Paste" "F.Mask") (roundrect_rratio 0.25)
      (net 90 "Net-(U2-VIN)") (pintype "passive"))
  )
	(footprint "antmicro-footprints:Resonator_SMD_Abracon_ABM8G_3.2x2.5mm" (layer "F.Cu")
    (at 122.998 76.12 180)
    (property "Author" "Antmicro")
    (property "License" "Apache-2.0")
    (property "MPN" "ABM8G-25.000MHZ-18-D2Y-T3")
    (property "Manufacturer" "Abracon")
    (property "Sheetfile" "tb.kicad_sch")
    (property "Sheetname" "TB Controller")
    (property "Val" "25 MHz")
    (property "ki_description" "Crystal, 25 MHz, SMD, 3.2mm x 2.5mm, 30 ppm, 18 pF, 20 ppm, ABM8G")
    (property "ki_keywords" "SMT, CERAMIC, OSCILLATOR")
    (attr smd)
    (fp_text reference "Y1" (at 0.824 1.825) (layer "F.SilkS")
        (effects (font (size 0.7 0.7) (thickness 0.15)) (justify left bottom))
    )
    (fp_text value "Resonator_25MHz_ABM8G" (at -1.75 2.548 180) (layer "F.Fab")
        (effects (font (size 0.7 0.7) (thickness 0.15)) (justify left bottom))
    )
    (fp_text user "License: Apache-2.0" (at -1.75 6.5 180) (layer "F.Fab") hide
        (effects (font (size 0.7 0.7) (thickness 0.15)) (justify left bottom))
    )
    (fp_text user "${REFERENCE}" (at -1.75 3.75 180) (layer "F.Fab") hide
        (effects (font (size 0.7 0.7) (thickness 0.15)) (justify left bottom))
    )
    (fp_text user "Author: Antmicro" (at -1.75 5 180) (layer "F.Fab") hide
        (effects (font (size 0.7 0.7) (thickness 0.15)) (justify left bottom))
    )
    (fp_line (start -1.6 0.3) (end -1.6 -0.2)
      (stroke (width 0.15) (type solid)) (layer "F.SilkS"))
    (fp_line (start -0.35 -1.25) (end 0.45 -1.25)
      (stroke (width 0.15) (type solid)) (layer "F.SilkS"))
    (fp_line (start -0.35 1.25) (end 0.45 1.25)
      (stroke (width 0.15) (type solid)) (layer "F.SilkS"))
    (fp_line (start 1.6 0.3) (end 1.6 -0.2)
      (stroke (width 0.15) (type solid)) (layer "F.SilkS"))
    (fp_circle (center -1.75 1.5) (end -1.7 1.5)
      (stroke (width 0.15) (type solid)) (fill none) (layer "F.SilkS"))
    (fp_rect (start -1.907 -1.55) (end 2.006 1.649)
      (stroke (width 0.05) (type solid)) (fill none) (layer "F.CrtYd"))
    (pad "1" smd roundrect (at -1.101 0.949 180) (size 1.3 1.1) (layers "F.Cu" "F.Paste" "F.Mask") (roundrect_rratio 0)
      (chamfer_ratio 0.2) (chamfer bottom_left)
      (net 115 "Net-(U6-XOUT)") (pintype "passive"))
    (pad "2" smd rect (at 1.199 0.949 180) (size 1.3 1.1) (layers "F.Cu" "F.Paste" "F.Mask")
      (net 1 "GND") (pinfunction "SH") (pintype "passive"))
    (pad "3" smd rect (at 1.199 -0.85 180) (size 1.3 1.1) (layers "F.Cu" "F.Paste" "F.Mask")
      (net 116 "Net-(U6-XIN{slash}CLKIN)") (pintype "passive"))
    (pad "4" smd rect (at -1.101 -0.85 180) (size 1.3 1.1) (layers "F.Cu" "F.Paste" "F.Mask")
      (net 1 "GND") (pinfunction "SH") (pintype "passive"))
  )
	(footprint "antmicro-footprints:C_1206_3216Metric" (layer "F.Cu")
    (at 111.110001 64.255 90)
    (descr "Capacitor SMD 1206")
    (tags "capacitor SMD 1206")
    (property "Author" "Antmicro")
    (property "Dielectric" "")
    (property "License" "Apache-2.0")
    (property "MPN" "3216X5R1V226M160AC")
    (property "Manufacturer" "TDK")
    (property "Sheetfile" "power.kicad_sch")
    (property "Sheetname" "Power")
    (property "Val" "22u")
    (property "Voltage" "35V")
    (property "ki_description" "SMD Multilayer Ceramic Capacitors, 22µF, 35V, X5R, 1206 [2316 Metric], 20% ")
    (property "ki_keywords" "1206, SMT, CAPACITOR, PASSIVE, CERAMIC, MLCC")
    (attr smd)
    (fp_text reference "C15" (at -4.325 0.395999 90) (layer "F.SilkS")
        (effects (font (size 0.7 0.7) (thickness 0.15)) (justify left bottom))
    )
    (fp_text value "C_22u_1206_35V" (at 0 2.101 90) (layer "F.Fab")
        (effects (font (size 0.7 0.7) (thickness 0.15)) (justify left bottom))
    )
    (fp_text user "Author: Antmicro" (at -2.625 5.301 90) (layer "F.Fab") hide
        (effects (font (size 0.7 0.7) (thickness 0.15)) (justify left bottom))
    )
    (fp_text user "${REFERENCE}" (at -2.625 4.101 90) (layer "F.Fab") hide
        (effects (font (size 0.7 0.7) (thickness 0.15)) (justify left bottom))
    )
    (fp_text user "License: Apache-2.0" (at -2.625 6.501 90) (layer "F.Fab") hide
        (effects (font (size 0.7 0.7) (thickness 0.15)) (justify left bottom))
    )
    (fp_line (start 0.8 -0.899) (end -0.8 -0.899)
      (stroke (width 0.15) (type solid)) (layer "F.SilkS"))
    (fp_line (start 0.8 0.901) (end -0.8 0.901)
      (stroke (width 0.15) (type solid)) (layer "F.SilkS"))
    (fp_rect (start -2.325 -1.15) (end 2.325 1.15)
      (stroke (width 0.05) (type default)) (fill none) (layer "F.CrtYd"))
    (fp_rect (start -1.6 -0.799) (end 1.6 0.801)
      (stroke (width 0.15) (type solid)) (fill none) (layer "F.Fab"))
    (pad "1" smd roundrect (at -1.5 0.001 90) (size 1.15 1.8) (layers "F.Cu" "F.Paste" "F.Mask") (roundrect_rratio 0.25)
      (net 1 "GND") (pintype "passive"))
    (pad "2" smd roundrect (at 1.5 0.001 90) (size 1.15 1.8) (layers "F.Cu" "F.Paste" "F.Mask") (roundrect_rratio 0.25)
      (net 90 "Net-(U2-VIN)") (pintype "passive"))
  )
	(footprint "antmicro-footprints:C_0805_2012Metric" (layer "F.Cu")
    (at 114.35 93.95 180)
    (descr "Capacitor SMD 0805")
    (tags "capacitor SMD 0805")
    (property "Author" "Antmicro")
    (property "Dielectric" "")
    (property "License" "Apache-2.0")
    (property "MPN" "GRM21BR6YA106KE43L")
    (property "Manufacturer" "Murata")
    (property "Sheetfile" "connectors.kicad_sch")
    (property "Sheetname" "Connectors")
    (property "Val" "10u")
    (property "Voltage" "35V")
    (property "ki_description" "SMD Multilayer Ceramic Capacitor, 10 µF, 35 V, 0805 [2012 Metric], ± 10%, X5R, GRM Series")
    (property "ki_keywords" "0805, SMT, CAPACITOR, PASSIVE")
    (attr smd)
    (fp_text reference "C1" (at -1.982 -0.538 180) (layer "F.SilkS")
        (effects (font (size 0.7 0.7) (thickness 0.15)) (justify left bottom))
    )
    (fp_text value "C_10u_0805_35V" (at -2.055717 1.963152 180) (layer "F.Fab")
        (effects (font (size 0.7 0.7) (thickness 0.15)) (justify left bottom))
    )
    (fp_text user "${REFERENCE}" (at -1.9 3.947 180) (layer "F.Fab") hide
        (effects (font (size 0.7 0.7) (thickness 0.15)) (justify left bottom))
    )
    (fp_text user "Author: Antmicro" (at -1.9 5.947 180) (layer "F.Fab") hide
        (effects (font (size 0.7 0.7) (thickness 0.15)) (justify left bottom))
    )
    (fp_text user "License: Apache-2.0" (at -1.9 4.947 180) (layer "F.Fab") hide
        (effects (font (size 0.7 0.7) (thickness 0.15)) (justify left bottom))
    )
    (fp_line (start -0.3 -0.7) (end 0.3 -0.7)
      (stroke (width 0.15) (type solid)) (layer "F.SilkS"))
    (fp_line (start -0.3 0.7) (end 0.3 0.7)
      (stroke (width 0.15) (type solid)) (layer "F.SilkS"))
    (fp_rect (start 1.95 -0.9) (end -1.95 0.9)
      (stroke (width 0.05) (type default)) (fill none) (layer "F.CrtYd"))
    (fp_rect (start -0.95 -0.675) (end 0.95 0.675)
      (stroke (width 0.15) (type solid)) (fill none) (layer "F.Fab"))
    (pad "1" smd roundrect (at -1.1 0 180) (size 1.2 1.3) (layers "F.Cu" "F.Paste" "F.Mask") (roundrect_rratio 0.25)
      (net 1 "GND") (pintype "passive"))
    (pad "2" smd roundrect (at 1.1 0 180) (size 1.2 1.3) (layers "F.Cu" "F.Paste" "F.Mask") (roundrect_rratio 0.25)
      (net 8 "12V0_PCIE") (pintype "passive"))
  )
	(footprint "antmicro-footprints:SOIC-8_3.9x4.9x1.75mm_P1.27mm" (layer "F.Cu")
    (at 137.147856 62.3)
    (property "Author" "Antmicro")
    (property "License" "Apache-2.0")
    (property "MPN" "MX25L8006EM1I-12G")
    (property "Manufacturer" "Macronix")
    (property "Sheetfile" "tb.kicad_sch")
    (property "Sheetname" "TB Controller")
    (property "ki_description" "FLASH - NOR Memory IC 8Mbit SPI 86 MHz 8-SOP")
    (property "ki_keywords" "SMT, MEMORY, IC, FLASH")
    (attr smd)
    (fp_text reference "U5" (at -1.892856 -3.245) (layer "F.SilkS")
        (effects (font (size 0.7 0.7) (thickness 0.15)) (justify left bottom))
    )
    (fp_text value "MX25L8006EM1I-12G" (at 0 3.65) (layer "F.Fab")
        (effects (font (size 0.7 0.7) (thickness 0.15)) (justify left bottom))
    )
    (fp_text user "${REFERENCE}" (at -3.476 7.099) (layer "F.Fab") hide
        (effects (font (size 0.7 0.7) (thickness 0.15)) (justify left bottom))
    )
    (fp_text user "Author: Antmicro" (at -3.476 6.099) (layer "F.Fab") hide
        (effects (font (size 0.7 0.7) (thickness 0.15)) (justify left bottom))
    )
    (fp_text user "License: Apache-2.0" (at -3.476 5.099) (layer "F.Fab") hide
        (effects (font (size 0.7 0.7) (thickness 0.15)) (justify left bottom))
    )
    (fp_line (start -1.95 -2.452) (end 1.95 -2.45)
      (stroke (width 0.15) (type solid)) (layer "F.SilkS"))
    (fp_line (start -1.95 2.45) (end 1.95 2.45)
      (stroke (width 0.15) (type solid)) (layer "F.SilkS"))
    (fp_circle (center -2.4 -2.45) (end -2.35 -2.4)
      (stroke (width 0.15) (type solid)) (fill solid) (layer "F.SilkS"))
    (fp_rect (start -3.625 -2.7) (end 3.625 2.7)
      (stroke (width 0.05) (type solid)) (fill none) (layer "F.CrtYd"))
    (fp_line (start -1.95 -1.18) (end -0.683 -2.452)
      (stroke (width 0.15) (type solid)) (layer "F.Fab"))
    (fp_line (start -1.95 2.45) (end -1.95 -1.18)
      (stroke (width 0.15) (type solid)) (layer "F.Fab"))
    (fp_line (start -0.683 -2.452) (end 1.949 -2.452)
      (stroke (width 0.15) (type solid)) (layer "F.Fab"))
    (fp_line (start 1.949 -2.452) (end 1.949 2.45)
      (stroke (width 0.15) (type solid)) (layer "F.Fab"))
    (fp_line (start 1.949 2.45) (end -1.95 2.45)
      (stroke (width 0.15) (type solid)) (layer "F.Fab"))
    (pad "1" smd roundrect (at -2.714 -1.905 90) (size 0.65 1.525) (layers "F.Cu" "F.Paste" "F.Mask") (roundrect_rratio 0.25)
      (net 65 "SPI_CS") (pinfunction "~{CS}") (pintype "input"))
    (pad "2" smd roundrect (at -2.714 -0.635 90) (size 0.65 1.525) (layers "F.Cu" "F.Paste" "F.Mask") (roundrect_rratio 0.25)
      (net 63 "SPI_MISO") (pinfunction "SO/IO1") (pintype "input"))
    (pad "3" smd roundrect (at -2.714 0.632 90) (size 0.65 1.525) (layers "F.Cu" "F.Paste" "F.Mask") (roundrect_rratio 0.25)
      (net 64 "/TB Controller/FLASH_WP") (pinfunction "~{WP}") (pintype "input"))
    (pad "4" smd roundrect (at -2.714 1.902 90) (size 0.65 1.525) (layers "F.Cu" "F.Paste" "F.Mask") (roundrect_rratio 0.25)
      (net 1 "GND") (pinfunction "GND") (pintype "power_in"))
    (pad "5" smd roundrect (at 2.712 1.902 90) (size 0.65 1.525) (layers "F.Cu" "F.Paste" "F.Mask") (roundrect_rratio 0.25)
      (net 69 "SPI_MOSI") (pinfunction "SI/IO0") (pintype "input"))
    (pad "6" smd roundrect (at 2.712 0.632 90) (size 0.65 1.525) (layers "F.Cu" "F.Paste" "F.Mask") (roundrect_rratio 0.25)
      (net 68 "SPI_SCLK") (pinfunction "SCLK") (pintype "input"))
    (pad "7" smd roundrect (at 2.712 -0.635 90) (size 0.65 1.525) (layers "F.Cu" "F.Paste" "F.Mask") (roundrect_rratio 0.25)
      (net 89 "/TB Controller/FLASH_HOLD") (pinfunction "~{HOLD}") (pintype "input"))
    (pad "8" smd roundrect (at 2.712 -1.905 90) (size 0.65 1.525) (layers "F.Cu" "F.Paste" "F.Mask") (roundrect_rratio 0.25)
      (net 2 "3V3_SYS") (pinfunction "VCC") (pintype "power_in"))
  )
)
